(kicad_pcb
	(version 20260206)
	(generator "pcbnew")
	(generator_version "10.0")
	(general
		(thickness 1.6)
		(legacy_teardrops no)
	)
	(paper "A4")
	(title_block
		(title "panther-plus-userver — 13130-1b_20150205.brd")
		(comment 1 "Honey Badger (Wiwynn) / footprint 282 of 1509 (U13), pads 592-704 of 1283")
	)
	(layers
		(0 "F.Cu" signal "TOP")
		(4 "In1.Cu" signal "L2")
		(6 "In2.Cu" signal "L3")
		(8 "In3.Cu" signal "L4")
		(10 "In4.Cu" signal "L5")
		(12 "In5.Cu" signal "L6")
		(14 "In6.Cu" signal "L7")
		(16 "In7.Cu" signal "L8")
		(18 "In8.Cu" signal "L9")
		(20 "In9.Cu" signal "L10")
		(22 "In10.Cu" signal "L11")
		(2 "B.Cu" signal "BOTTOM")
		(9 "F.Adhes" user "F.Adhesive")
		(11 "B.Adhes" user "B.Adhesive")
		(13 "F.Paste" user "Package Geometry/Pastemask Top")
		(15 "B.Paste" user "Package Geometry/Pastemask Bottom")
		(5 "F.SilkS" user "Ref Des/Silkscreen Top")
		(7 "B.SilkS" user "Ref Des/Silkscreen Bottom")
		(1 "F.Mask" user "Board Geometry/Soldermask Top")
		(3 "B.Mask" user "Board Geometry/Soldermask Bottom")
		(17 "Dwgs.User" user "User.Drawings")
		(19 "Cmts.User" user "User.Comments")
		(21 "Eco1.User" user "User.Eco1")
		(23 "Eco2.User" user "User.Eco2")
		(25 "Edge.Cuts" user "Board Geometry/Outline")
		(27 "Margin" user)
		(31 "F.CrtYd" user "Package Geometry/Place Bound Top")
		(29 "B.CrtYd" user "Package Geometry/Place Bound Bottom")
		(35 "F.Fab" user "Ref Des/Assembly Top")
		(33 "B.Fab" user "Ref Des/Assembly Bottom")
	)
	(footprint ""
		(layer "F.Cu")
		(at 95.849948 -39.200074 180)
		(property "Reference" "U13"
			(at 0 0 180)
			(layer "F.SilkS")
			(hide yes)
			(effects
				(font
					(size 1.27 1.27)
				)
			)
		)
		(property "Value" "AVOTON-GP"
			(at -25.0317 -2.4892 180)
			(unlocked yes)
			(layer "F.Fab")
			(hide yes)
			(effects
				(font
					(size 1.016 1.016)
					(thickness 0.1524)
				)
			)
		)
		(property "Device Type" "BGA1283M3428-3H197"
			(at -25.0317 -4.0132 180)
			(unlocked yes)
			(layer "F.Fab")
			(hide yes)
			(effects
				(font
					(size 1.016 1.016)
					(thickness 0.1524)
				)
			)
		)
		(duplicate_pad_numbers_are_jumpers no)
		(pad "BD13" smd circle
			(at -10.16254 8.44042 180)
			(size 0.3048 0.3048)
			(layers "F.Cu" "F.Mask" "F.Paste")
			(net "M_A_MA4")
		)
		(pad "BD15" smd circle
			(at -9.4615 8.44042 180)
			(size 0.3048 0.3048)
			(layers "F.Cu" "F.Mask" "F.Paste")
			(net "M_A_MA9")
		)
		(pad "BD17" smd circle
			(at -8.17626 8.05942 180)
			(size 0.3048 0.3048)
			(layers "F.Cu" "F.Mask" "F.Paste")
			(net "PV_VDDR")
		)
		(pad "BD19" smd circle
			(at -7.47522 8.05942 180)
			(size 0.3048 0.3048)
			(layers "F.Cu" "F.Mask" "F.Paste")
			(net "M_A_CK_DN3")
		)
		(pad "BD21" smd circle
			(at -6.18998 8.44042 180)
			(size 0.3048 0.3048)
			(layers "F.Cu" "F.Mask" "F.Paste")
			(net "PV_VDDR")
		)
		(pad "BD23" smd circle
			(at -5.48894 8.44042 180)
			(size 0.3048 0.3048)
			(layers "F.Cu" "F.Mask" "F.Paste")
			(net "M_A_CS_N2")
		)
		(pad "BD25" smd circle
			(at -4.2037 8.05942 180)
			(size 0.3048 0.3048)
			(layers "F.Cu" "F.Mask" "F.Paste")
			(net "PV_VDDR")
		)
		(pad "BD26" smd circle
			(at -3.50266 8.05942 180)
			(size 0.3048 0.3048)
			(layers "F.Cu" "F.Mask" "F.Paste")
			(net "M_A_ODT0")
		)
		(pad "BD29" smd circle
			(at -2.21742 8.44042 180)
			(size 0.3048 0.3048)
			(layers "F.Cu" "F.Mask" "F.Paste")
			(net "M_A_DQS_DP4")
		)
		(pad "BD30" smd circle
			(at -1.51638 8.44042 180)
			(size 0.3048 0.3048)
			(layers "F.Cu" "F.Mask" "F.Paste")
			(net "M_A_DQ35")
		)
		(pad "BD32" smd circle
			(at -0.23114 8.05942 180)
			(size 0.3048 0.3048)
			(layers "F.Cu" "F.Mask" "F.Paste")
			(net "GND")
		)
		(pad "BD34" smd circle
			(at 0.4699 8.05942 180)
			(size 0.3048 0.3048)
			(layers "F.Cu" "F.Mask" "F.Paste")
			(net "GND")
		)
		(pad "BD37" smd circle
			(at 1.75514 8.44042 180)
			(size 0.3048 0.3048)
			(layers "F.Cu" "F.Mask" "F.Paste")
			(net "P2E_CPU_NGFF_RX_DP14")
		)
		(pad "BD38" smd circle
			(at 2.45618 8.44042 180)
			(size 0.3048 0.3048)
			(layers "F.Cu" "F.Mask" "F.Paste")
			(net "GND")
		)
		(pad "BD41" smd circle
			(at 3.74142 8.05942 180)
			(size 0.3048 0.3048)
			(layers "F.Cu" "F.Mask" "F.Paste")
			(net "GND")
		)
		(pad "BD42" smd circle
			(at 4.44246 8.05942 180)
			(size 0.3048 0.3048)
			(layers "F.Cu" "F.Mask" "F.Paste")
			(net "Net_1367")
		)
		(pad "BD45" smd circle
			(at 5.7277 8.44042 180)
			(size 0.3048 0.3048)
			(layers "F.Cu" "F.Mask" "F.Paste")
			(net "GND")
		)
		(pad "BD46" smd circle
			(at 6.42874 8.44042 180)
			(size 0.3048 0.3048)
			(layers "F.Cu" "F.Mask" "F.Paste")
			(net "P2E_CPU_ETH10G_RX_DP9")
		)
		(pad "BD49" smd circle
			(at 7.71398 8.05942 180)
			(size 0.3048 0.3048)
			(layers "F.Cu" "F.Mask" "F.Paste")
			(net "CLK_100M_CLKBUFF_PCIE_DN")
		)
		(pad "BD50" smd circle
			(at 8.41502 8.05942 180)
			(size 0.3048 0.3048)
			(layers "F.Cu" "F.Mask" "F.Paste")
			(net "GND")
		)
		(pad "BD53" smd circle
			(at 9.70026 8.44042 180)
			(size 0.3048 0.3048)
			(layers "F.Cu" "F.Mask" "F.Paste")
			(net "GND")
		)
		(pad "BD54" smd circle
			(at 10.4013 8.44042 180)
			(size 0.3048 0.3048)
			(layers "F.Cu" "F.Mask" "F.Paste")
			(net "P2E_CPU_SAS_RX_DP5")
		)
		(pad "BD59" smd circle
			(at 12.58316 8.17626 180)
			(size 0.3048 0.3048)
			(layers "F.Cu" "F.Mask" "F.Paste")
			(net "GND")
		)
		(pad "BD60" smd circle
			(at 13.34516 8.17626 180)
			(size 0.3048 0.3048)
			(layers "F.Cu" "F.Mask" "F.Paste")
			(net "GND")
		)
		(pad "BD62" smd circle
			(at 14.06398 8.39216 180)
			(size 0.3048 0.3048)
			(layers "F.Cu" "F.Mask" "F.Paste")
			(net "GND")
		)
		(pad "BD63" smd circle
			(at 14.75232 8.22198 180)
			(size 0.3048 0.3048)
			(layers "F.Cu" "F.Mask" "F.Paste")
			(net "GND")
		)
		(pad "BD65" smd circle
			(at 15.80642 8.14324 180)
			(size 0.3048 0.3048)
			(layers "F.Cu" "F.Mask" "F.Paste")
			(net "GND")
		)
		(pad "BE5" smd circle
			(at -14.06398 8.5979 180)
			(size 0.3048 0.3048)
			(layers "F.Cu" "F.Mask" "F.Paste")
			(net "GND")
		)
		(pad "BE17" smd circle
			(at -8.17626 8.82142 180)
			(size 0.3048 0.3048)
			(layers "F.Cu" "F.Mask" "F.Paste")
			(net "PWRGD_DDR3_VCCA")
		)
		(pad "BE19" smd circle
			(at -7.47522 8.82142 180)
			(size 0.3048 0.3048)
			(layers "F.Cu" "F.Mask" "F.Paste")
			(net "PV_VDDR")
		)
		(pad "BE25" smd circle
			(at -4.2037 8.82142 180)
			(size 0.3048 0.3048)
			(layers "F.Cu" "F.Mask" "F.Paste")
			(net "M_A_CS_N0")
		)
		(pad "BE26" smd circle
			(at -3.50266 8.82142 180)
			(size 0.3048 0.3048)
			(layers "F.Cu" "F.Mask" "F.Paste")
			(net "PV_VDDR")
		)
		(pad "BE32" smd circle
			(at -0.23114 8.82142 180)
			(size 0.3048 0.3048)
			(layers "F.Cu" "F.Mask" "F.Paste")
			(net "GND")
		)
		(pad "BE34" smd circle
			(at 0.4699 8.82142 180)
			(size 0.3048 0.3048)
			(layers "F.Cu" "F.Mask" "F.Paste")
			(net "P2E_CPU_NGFF_RX_DP15")
		)
		(pad "BE41" smd circle
			(at 3.74142 8.82142 180)
			(size 0.3048 0.3048)
			(layers "F.Cu" "F.Mask" "F.Paste")
			(net "P2E_CPU_NGFF_RX_DP12")
		)
		(pad "BE42" smd circle
			(at 4.44246 8.82142 180)
			(size 0.3048 0.3048)
			(layers "F.Cu" "F.Mask" "F.Paste")
			(net "GND")
		)
		(pad "BE49" smd circle
			(at 7.71398 8.82142 180)
			(size 0.3048 0.3048)
			(layers "F.Cu" "F.Mask" "F.Paste")
			(net "GND")
		)
		(pad "BE50" smd circle
			(at 8.41502 8.82142 180)
			(size 0.3048 0.3048)
			(layers "F.Cu" "F.Mask" "F.Paste")
			(net "P2E_CPU_SAS_RX_DP7")
		)
		(pad "BE57" smd circle
			(at 11.68654 8.82142 180)
			(size 0.3048 0.3048)
			(layers "F.Cu" "F.Mask" "F.Paste")
			(net "GND")
		)
		(pad "BE63" smd circle
			(at 14.5415 8.9027 180)
			(size 0.3048 0.3048)
			(layers "F.Cu" "F.Mask" "F.Paste")
			(net "P2E_CPU_SAS_RX_DP0")
		)
		(pad "BE64" smd circle
			(at 15.3035 8.9535 180)
			(size 0.3048 0.3048)
			(layers "F.Cu" "F.Mask" "F.Paste")
			(net "P2E_CPU_SAS_RX_DN0")
		)
		(pad "BE66" smd oval
			(at 16.24838 8.9027 180)
			(size 0.3429 0.254)
			(layers "F.Cu" "F.Mask" "F.Paste")
			(net "GND")
		)
		(pad "BF1" smd oval
			(at -16.24838 9.10844 180)
			(size 0.3429 0.254)
			(layers "F.Cu" "F.Mask" "F.Paste")
			(net "GND")
		)
		(pad "BF3" smd circle
			(at -15.3035 9.05764 180)
			(size 0.3048 0.3048)
			(layers "F.Cu" "F.Mask" "F.Paste")
			(net "GND")
		)
		(pad "BF4" smd circle
			(at -14.5415 9.10844 180)
			(size 0.3048 0.3048)
			(layers "F.Cu" "F.Mask" "F.Paste")
			(net "GND")
		)
		(pad "BF13" smd circle
			(at -10.16254 9.20242 180)
			(size 0.3048 0.3048)
			(layers "F.Cu" "F.Mask" "F.Paste")
			(net "PV_VDDR")
		)
		(pad "BF15" smd circle
			(at -9.4615 9.20242 180)
			(size 0.3048 0.3048)
			(layers "F.Cu" "F.Mask" "F.Paste")
			(net "M_A_MA15")
		)
		(pad "BF21" smd circle
			(at -6.18998 9.20242 180)
			(size 0.3048 0.3048)
			(layers "F.Cu" "F.Mask" "F.Paste")
			(net "M_A_CK_DP1")
		)
		(pad "BF23" smd circle
			(at -5.48894 9.20242 180)
			(size 0.3048 0.3048)
			(layers "F.Cu" "F.Mask" "F.Paste")
			(net "PV_VDDR")
		)
		(pad "BF29" smd circle
			(at -2.21742 9.20242 180)
			(size 0.3048 0.3048)
			(layers "F.Cu" "F.Mask" "F.Paste")
			(net "GND")
		)
		(pad "BF30" smd circle
			(at -1.51638 9.20242 180)
			(size 0.3048 0.3048)
			(layers "F.Cu" "F.Mask" "F.Paste")
			(net "M_A_DQ34")
		)
		(pad "BF37" smd circle
			(at 1.75514 9.20242 180)
			(size 0.3048 0.3048)
			(layers "F.Cu" "F.Mask" "F.Paste")
			(net "P2E_CPU_NGFF_RX_DN14")
		)
		(pad "BF38" smd circle
			(at 2.45618 9.20242 180)
			(size 0.3048 0.3048)
			(layers "F.Cu" "F.Mask" "F.Paste")
			(net "P2E_CPU_NGFF_RX_DP13")
		)
		(pad "BF45" smd circle
			(at 5.7277 9.20242 180)
			(size 0.3048 0.3048)
			(layers "F.Cu" "F.Mask" "F.Paste")
			(net "P2E_CPU_ETH10G_RX_DP10")
		)
		(pad "BF46" smd circle
			(at 6.42874 9.20242 180)
			(size 0.3048 0.3048)
			(layers "F.Cu" "F.Mask" "F.Paste")
			(net "P2E_CPU_ETH10G_RX_DN9")
		)
		(pad "BF53" smd circle
			(at 9.70026 9.20242 180)
			(size 0.3048 0.3048)
			(layers "F.Cu" "F.Mask" "F.Paste")
			(net "P2E_CPU_SAS_RX_DP6")
		)
		(pad "BF54" smd circle
			(at 10.4013 9.20242 180)
			(size 0.3048 0.3048)
			(layers "F.Cu" "F.Mask" "F.Paste")
			(net "P2E_CPU_SAS_RX_DN5")
		)
		(pad "BF62" smd circle
			(at 14.06398 9.41324 180)
			(size 0.3048 0.3048)
			(layers "F.Cu" "F.Mask" "F.Paste")
			(net "GND")
		)
		(pad "BG1" smd circle
			(at -16.11122 9.86028 180)
			(size 0.4064 0.4064)
			(layers "F.Cu" "F.Mask" "F.Paste")
			(net "GND")
		)
		(pad "BG4" smd circle
			(at -14.75232 9.78916 180)
			(size 0.3048 0.3048)
			(layers "F.Cu" "F.Mask" "F.Paste")
			(net "M_A_CKE0")
		)
		(pad "BG5" smd circle
			(at -14.06398 9.62152 180)
			(size 0.3048 0.3048)
			(layers "F.Cu" "F.Mask" "F.Paste")
			(net "M_A_CKE2")
		)
		(pad "BG8" smd circle
			(at -12.96416 9.70026 180)
			(size 0.3048 0.3048)
			(layers "F.Cu" "F.Mask" "F.Paste")
			(net "M_A_MA11")
		)
		(pad "BG9" smd circle
			(at -12.20216 9.70026 180)
			(size 0.3048 0.3048)
			(layers "F.Cu" "F.Mask" "F.Paste")
			(net "PV_VDDR")
		)
		(pad "BG11" smd circle
			(at -11.44778 9.58342 180)
			(size 0.3048 0.3048)
			(layers "F.Cu" "F.Mask" "F.Paste")
			(net "M_A_MA3")
		)
		(pad "BG13" smd circle
			(at -10.16254 9.96442 180)
			(size 0.3048 0.3048)
			(layers "F.Cu" "F.Mask" "F.Paste")
			(net "M_A_MA2")
		)
		(pad "BG15" smd circle
			(at -9.4615 9.96442 180)
			(size 0.3048 0.3048)
			(layers "F.Cu" "F.Mask" "F.Paste")
			(net "PV_VDDR")
		)
		(pad "BG17" smd circle
			(at -8.17626 9.58342 180)
			(size 0.3048 0.3048)
			(layers "F.Cu" "F.Mask" "F.Paste")
			(net "M_DRAM_PWROK")
		)
		(pad "BG19" smd circle
			(at -7.47522 9.58342 180)
			(size 0.3048 0.3048)
			(layers "F.Cu" "F.Mask" "F.Paste")
			(net "M_A_CK_DP2")
		)
		(pad "BG21" smd circle
			(at -6.18998 9.96442 180)
			(size 0.3048 0.3048)
			(layers "F.Cu" "F.Mask" "F.Paste")
			(net "M_A_CK_DN1")
		)
		(pad "BG23" smd circle
			(at -5.48894 9.96442 180)
			(size 0.3048 0.3048)
			(layers "F.Cu" "F.Mask" "F.Paste")
			(net "M_A_RAS#")
		)
		(pad "BG25" smd circle
			(at -4.2037 9.58342 180)
			(size 0.3048 0.3048)
			(layers "F.Cu" "F.Mask" "F.Paste")
			(net "M_A_ODT3")
		)
		(pad "BG26" smd circle
			(at -3.50266 9.58342 180)
			(size 0.3048 0.3048)
			(layers "F.Cu" "F.Mask" "F.Paste")
			(net "M_A_CS_N3")
		)
		(pad "BG29" smd circle
			(at -2.21742 9.96442 180)
			(size 0.3048 0.3048)
			(layers "F.Cu" "F.Mask" "F.Paste")
			(net "M_A_DQ38")
		)
		(pad "BG30" smd circle
			(at -1.51638 9.96442 180)
			(size 0.3048 0.3048)
			(layers "F.Cu" "F.Mask" "F.Paste")
			(net "M_A_DQ39")
		)
		(pad "BG32" smd circle
			(at -0.23114 9.58342 180)
			(size 0.3048 0.3048)
			(layers "F.Cu" "F.Mask" "F.Paste")
			(net "GND")
		)
		(pad "BG34" smd circle
			(at 0.4699 9.58342 180)
			(size 0.3048 0.3048)
			(layers "F.Cu" "F.Mask" "F.Paste")
			(net "P2E_CPU_NGFF_RX_DN15")
		)
		(pad "BG37" smd circle
			(at 1.75514 9.96442 180)
			(size 0.3048 0.3048)
			(layers "F.Cu" "F.Mask" "F.Paste")
			(net "GND")
		)
		(pad "BG38" smd circle
			(at 2.45618 9.96442 180)
			(size 0.3048 0.3048)
			(layers "F.Cu" "F.Mask" "F.Paste")
			(net "P2E_CPU_NGFF_RX_DN13")
		)
		(pad "BG41" smd circle
			(at 3.74142 9.58342 180)
			(size 0.3048 0.3048)
			(layers "F.Cu" "F.Mask" "F.Paste")
			(net "P2E_CPU_NGFF_RX_DN12")
		)
		(pad "BG42" smd circle
			(at 4.44246 9.58342 180)
			(size 0.3048 0.3048)
			(layers "F.Cu" "F.Mask" "F.Paste")
			(net "P2E_CPU_ETH10G_RX_DP11")
		)
		(pad "BG45" smd circle
			(at 5.7277 9.96442 180)
			(size 0.3048 0.3048)
			(layers "F.Cu" "F.Mask" "F.Paste")
			(net "P2E_CPU_ETH10G_RX_DN10")
		)
		(pad "BG46" smd circle
			(at 6.42874 9.96442 180)
			(size 0.3048 0.3048)
			(layers "F.Cu" "F.Mask" "F.Paste")
			(net "GND")
		)
		(pad "BG49" smd circle
			(at 7.71398 9.58342 180)
			(size 0.3048 0.3048)
			(layers "F.Cu" "F.Mask" "F.Paste")
			(net "P2E_CPU_ETH10G_RX_DP8")
		)
		(pad "BG50" smd circle
			(at 8.41502 9.58342 180)
			(size 0.3048 0.3048)
			(layers "F.Cu" "F.Mask" "F.Paste")
			(net "P2E_CPU_SAS_RX_DN7")
		)
		(pad "BG53" smd circle
			(at 9.70026 9.96442 180)
			(size 0.3048 0.3048)
			(layers "F.Cu" "F.Mask" "F.Paste")
			(net "P2E_CPU_SAS_RX_DN6")
		)
		(pad "BG54" smd circle
			(at 10.4013 9.96442 180)
			(size 0.3048 0.3048)
			(layers "F.Cu" "F.Mask" "F.Paste")
			(net "GND")
		)
		(pad "BG57" smd circle
			(at 11.68654 9.58342 180)
			(size 0.3048 0.3048)
			(layers "F.Cu" "F.Mask" "F.Paste")
			(net "P2E_CPU_SAS_RX_DP4")
		)
		(pad "BG58" smd circle
			(at 12.38758 9.58342 180)
			(size 0.3048 0.3048)
			(layers "F.Cu" "F.Mask" "F.Paste")
			(net "P2E_CPU_SAS_RX_DP3")
		)
		(pad "BG63" smd circle
			(at 14.75232 9.58088 180)
			(size 0.3048 0.3048)
			(layers "F.Cu" "F.Mask" "F.Paste")
			(net "GND")
		)
		(pad "BG66" smd circle
			(at 16.11122 9.86028 180)
			(size 0.4064 0.4064)
			(layers "F.Cu" "F.Mask" "F.Paste")
			(net "GND")
		)
		(pad "BH3" smd circle
			(at -15.29842 10.31748 180)
			(size 0.3048 0.3048)
			(layers "F.Cu" "F.Mask" "F.Paste")
			(net "M_A_CKE3")
		)
		(pad "BH5" smd circle
			(at -14.01318 10.32256 180)
			(size 0.3048 0.3048)
			(layers "F.Cu" "F.Mask" "F.Paste")
			(net "M_A_CKE1")
		)
		(pad "BH8" smd circle
			(at -12.58316 10.34542 180)
			(size 0.3048 0.3048)
			(layers "F.Cu" "F.Mask" "F.Paste")
			(net "M_A_MA7")
		)
		(pad "BH11" smd circle
			(at -11.44778 10.34542 180)
			(size 0.3048 0.3048)
			(layers "F.Cu" "F.Mask" "F.Paste")
			(net "M_A_MA0")
		)
		(pad "BH17" smd circle
			(at -8.17626 10.34542 180)
			(size 0.3048 0.3048)
			(layers "F.Cu" "F.Mask" "F.Paste")
			(net "PV_VDDR")
		)
		(pad "BH19" smd circle
			(at -7.47522 10.34542 180)
			(size 0.3048 0.3048)
			(layers "F.Cu" "F.Mask" "F.Paste")
			(net "M_A_CK_DN2")
		)
		(pad "BH25" smd circle
			(at -4.2037 10.34542 180)
			(size 0.3048 0.3048)
			(layers "F.Cu" "F.Mask" "F.Paste")
			(net "M_A_ODT2")
		)
		(pad "BH26" smd circle
			(at -3.50266 10.34542 180)
			(size 0.3048 0.3048)
			(layers "F.Cu" "F.Mask" "F.Paste")
			(net "M_A_CAS#")
		)
		(pad "BH32" smd circle
			(at -0.23114 10.34542 180)
			(size 0.3048 0.3048)
			(layers "F.Cu" "F.Mask" "F.Paste")
			(net "GND")
		)
		(pad "BH34" smd circle
			(at 0.4699 10.34542 180)
			(size 0.3048 0.3048)
			(layers "F.Cu" "F.Mask" "F.Paste")
			(net "GND")
		)
		(pad "BH41" smd circle
			(at 3.74142 10.34542 180)
			(size 0.3048 0.3048)
			(layers "F.Cu" "F.Mask" "F.Paste")
			(net "GND")
		)
		(pad "BH42" smd circle
			(at 4.44246 10.34542 180)
			(size 0.3048 0.3048)
			(layers "F.Cu" "F.Mask" "F.Paste")
			(net "P2E_CPU_ETH10G_RX_DN11")
		)
		(pad "BH49" smd circle
			(at 7.71398 10.34542 180)
			(size 0.3048 0.3048)
			(layers "F.Cu" "F.Mask" "F.Paste")
			(net "P2E_CPU_ETH10G_RX_DN8")
		)
		(pad "BH50" smd circle
			(at 8.41502 10.34542 180)
			(size 0.3048 0.3048)
			(layers "F.Cu" "F.Mask" "F.Paste")
			(net "GND")
		)
		(pad "BH57" smd circle
			(at 11.68654 10.34542 180)
			(size 0.3048 0.3048)
			(layers "F.Cu" "F.Mask" "F.Paste")
			(net "P2E_CPU_SAS_RX_DN4")
		)
		(pad "BH58" smd circle
			(at 12.38758 10.34542 180)
			(size 0.3048 0.3048)
			(layers "F.Cu" "F.Mask" "F.Paste")
			(net "P2E_CPU_SAS_RX_DN3")
		)
		(pad "BH60" smd circle
			(at 13.34516 10.16254 180)
			(size 0.3048 0.3048)
			(layers "F.Cu" "F.Mask" "F.Paste")
			(net "GND")
		)
		(pad "BH62" smd circle
			(at 14.08176 10.11936 180)
			(size 0.3048 0.3048)
			(layers "F.Cu" "F.Mask" "F.Paste")
			(net "GND")
		)
		(pad "BH64" smd circle
			(at 15.29842 10.1092 180)
			(size 0.3048 0.3048)
			(layers "F.Cu" "F.Mask" "F.Paste")
			(net "P2E_CPU_SAS_RX_DN1")
		)
		(pad "BJ1" smd circle
			(at -16.11122 10.67308 180)
			(size 0.4064 0.4064)
			(layers "F.Cu" "F.Mask" "F.Paste")
			(net "GND")
		)
		(pad "BJ4" smd circle
			(at -14.89964 10.90422 180)
			(size 0.3048 0.3048)
			(layers "F.Cu" "F.Mask" "F.Paste")
			(net "PV_VDDR")
		)
		(pad "BJ62" smd circle
			(at 14.20368 10.81278 180)
			(size 0.3048 0.3048)
			(layers "F.Cu" "F.Mask" "F.Paste")
			(net "P2E_CPU_SAS_RX_DP2")
		)
		(pad "BJ63" smd circle
			(at 14.89964 10.69594 180)
			(size 0.3048 0.3048)
			(layers "F.Cu" "F.Mask" "F.Paste")
			(net "P2E_CPU_SAS_RX_DP1")
		)
	)
)
